# T6G (Grand Teton) — schematic netlist excerpt (pin names and nets, part order shuffled) for the footprints in the layout excerpt that follows; sources: Cadence DE-HDL packaged netlist, KiCad conversion of 04192023_DAF0TMB3IC0_F0TG_MB_C_brd_V02_OCP.brd

R3263  Q_RES  0 5% EMPTY  pkg 0402LF  page 247 : A = HP_LVC3_OCP_V3_1_R_EN ; B = P3V3_OCP_SFF_EN_R
R9007  Q_RES  100K 1% EMPTY  pkg 0402LF  page 123 : A = PRSNT_CABLE_SWB_B2_N ; B = GND

(kicad_pcb
	(version 20260206)
	(generator "pcbnew")
	(generator_version "10.0")
	(general
		(thickness 1.6)
		(legacy_teardrops no)
	)
	(paper "A4")
	(title_block
		(title "04192023_DAF0TMB3IC0_F0TG_MB_C_brd_V02_OCP.brd")
		(comment 1 "Grand Teton / footprints 1905-1906 of 8354")
	)
	(layers
		(0 "F.Cu" signal "TOP")
		(4 "In1.Cu" signal "GND")
		(6 "In2.Cu" signal "IN1")
		(8 "In3.Cu" signal "GND1")
		(10 "In4.Cu" signal "IN2")
		(12 "In5.Cu" signal "GND2")
		(14 "In6.Cu" signal "IN3")
		(16 "In7.Cu" signal "GND3")
		(18 "In8.Cu" signal "VCC")
		(20 "In9.Cu" signal "VCC1")
		(22 "In10.Cu" signal "GND4")
		(24 "In11.Cu" signal "IN4")
		(26 "In12.Cu" signal "GND5")
		(28 "In13.Cu" signal "IN5")
		(30 "In14.Cu" signal "GND6")
		(32 "In15.Cu" signal "IN6")
		(34 "In16.Cu" signal "GND7")
		(2 "B.Cu" signal "BOTTOM")
		(9 "F.Adhes" user "F.Adhesive")
		(11 "B.Adhes" user "B.Adhesive")
		(13 "F.Paste" user "Package Geometry/Pastemask Top")
		(15 "B.Paste" user "Package Geometry/Pastemask Bottom")
		(5 "F.SilkS" user "Ref Des/Silkscreen Top")
		(7 "B.SilkS" user "Ref Des/Silkscreen Bottom")
		(1 "F.Mask" user "Board Geometry/Soldermask Top")
		(3 "B.Mask" user "Board Geometry/Soldermask Bottom")
		(17 "Dwgs.User" user "User.Drawings")
		(19 "Cmts.User" user "User.Comments")
		(21 "Eco1.User" user "User.Eco1")
		(23 "Eco2.User" user "User.Eco2")
		(25 "Edge.Cuts" user "Board Geometry/Outline")
		(27 "Margin" user)
		(31 "F.CrtYd" user "Package Geometry/Place Bound Top")
		(29 "B.CrtYd" user "Package Geometry/Place Bound Bottom")
		(35 "F.Fab" user "Ref Des/Assembly Top")
		(33 "B.Fab" user "Ref Des/Assembly Bottom")
	)
	(footprint ""
		(layer "F.Cu")
		(at 172.54347 -418.551868 180)
		(property "Reference" "R9007"
			(at 0 0 180)
			(layer "F.SilkS")
			(hide yes)
			(effects
				(font
					(size 1.27 1.27)
				)
			)
		)
		(property "Value" ""
			(at 0 0 180)
			(layer "F.Fab")
			(effects
				(font
					(size 1.27 1.27)
				)
			)
		)
		(duplicate_pad_numbers_are_jumpers no)
		(fp_line
			(start 0.7874 0.4064)
			(end -0.7874 0.4064)
			(stroke
				(width 0.1524)
				(type default)
			)
			(layer "F.SilkS")
		)
		(fp_line
			(start 0.7874 -0.4064)
			(end 0.7874 0.4064)
			(stroke
				(width 0.1524)
				(type default)
			)
			(layer "F.SilkS")
		)
		(fp_line
			(start -0.7874 0.4064)
			(end -0.7874 -0.4064)
			(stroke
				(width 0.1524)
				(type default)
			)
			(layer "F.SilkS")
		)
		(fp_line
			(start -0.7874 -0.4064)
			(end 0.7874 -0.4064)
			(stroke
				(width 0.1524)
				(type default)
			)
			(layer "F.SilkS")
		)
		(fp_line
			(start 0.67945 0.3048)
			(end 0.120396 0.3048)
			(stroke
				(width 0.1)
				(type default)
			)
			(layer "F.Fab")
		)
		(fp_line
			(start 0.67945 -0.3048)
			(end 0.67945 0.3048)
			(stroke
				(width 0.1)
				(type default)
			)
			(layer "F.Fab")
		)
		(fp_line
			(start 0.12065 -0.2794)
			(end 0.12065 -0.3048)
			(stroke
				(width 0.1)
				(type default)
			)
			(layer "F.Fab")
		)
		(fp_line
			(start 0.12065 -0.3048)
			(end 0.67945 -0.3048)
			(stroke
				(width 0.1)
				(type default)
			)
			(layer "F.Fab")
		)
		(fp_line
			(start 0.120396 0.3048)
			(end 0.120396 0.2794)
			(stroke
				(width 0.1)
				(type default)
			)
			(layer "F.Fab")
		)
		(fp_line
			(start 0.120396 0.2794)
			(end -0.12065 0.2794)
			(stroke
				(width 0.1)
				(type default)
			)
			(layer "F.Fab")
		)
		(fp_line
			(start -0.12065 0.3048)
			(end -0.67945 0.3048)
			(stroke
				(width 0.1)
				(type default)
			)
			(layer "F.Fab")
		)
		(fp_line
			(start -0.12065 0.2794)
			(end -0.12065 0.3048)
			(stroke
				(width 0.1)
				(type default)
			)
			(layer "F.Fab")
		)
		(fp_line
			(start -0.12065 -0.2794)
			(end 0.12065 -0.2794)
			(stroke
				(width 0.1)
				(type default)
			)
			(layer "F.Fab")
		)
		(fp_line
			(start -0.12065 -0.305054)
			(end -0.12065 -0.2794)
			(stroke
				(width 0.1)
				(type default)
			)
			(layer "F.Fab")
		)
		(fp_line
			(start -0.67945 0.3048)
			(end -0.67945 -0.305054)
			(stroke
				(width 0.1)
				(type default)
			)
			(layer "F.Fab")
		)
		(fp_line
			(start -0.67945 -0.305054)
			(end -0.12065 -0.305054)
			(stroke
				(width 0.1)
				(type default)
			)
			(layer "F.Fab")
		)
		(pad "1" smd circle
			(at -0.40005 0 180)
			(size 0 0)
			(layers "F.Cu" "F.Mask" "F.Paste")
			(net "PRSNT_CABLE_SWB_B2_N")
		)
		(pad "2" smd circle
			(at 0.40005 0 180)
			(size 0 0)
			(layers "F.Cu" "F.Mask" "F.Paste")
			(net "GND")
		)
	)
	(footprint ""
		(layer "F.Cu")
		(at 412.472886 -72.832468)
		(property "Reference" "R3263"
			(at 0 0 0)
			(layer "F.SilkS")
			(hide yes)
			(effects
				(font
					(size 1.27 1.27)
				)
			)
		)
		(property "Value" ""
			(at 0 0 0)
			(layer "F.Fab")
			(effects
				(font
					(size 1.27 1.27)
				)
			)
		)
		(duplicate_pad_numbers_are_jumpers no)
		(fp_line
			(start -0.7874 -0.4064)
			(end 0.7874 -0.4064)
			(stroke
				(width 0.1524)
				(type default)
			)
			(layer "F.SilkS")
		)
		(fp_line
			(start -0.7874 0.4064)
			(end -0.7874 -0.4064)
			(stroke
				(width 0.1524)
				(type default)
			)
			(layer "F.SilkS")
		)
		(fp_line
			(start 0.7874 -0.4064)
			(end 0.7874 0.4064)
			(stroke
				(width 0.1524)
				(type default)
			)
			(layer "F.SilkS")
		)
		(fp_line
			(start 0.7874 0.4064)
			(end -0.7874 0.4064)
			(stroke
				(width 0.1524)
				(type default)
			)
			(layer "F.SilkS")
		)
		(fp_line
			(start -0.67945 -0.305054)
			(end -0.12065 -0.305054)
			(stroke
				(width 0.1)
				(type default)
			)
			(layer "F.Fab")
		)
		(fp_line
			(start -0.67945 0.3048)
			(end -0.67945 -0.305054)
			(stroke
				(width 0.1)
				(type default)
			)
			(layer "F.Fab")
		)
		(fp_line
			(start -0.12065 -0.305054)
			(end -0.12065 -0.2794)
			(stroke
				(width 0.1)
				(type default)
			)
			(layer "F.Fab")
		)
		(fp_line
			(start -0.12065 -0.2794)
			(end 0.12065 -0.2794)
			(stroke
				(width 0.1)
				(type default)
			)
			(layer "F.Fab")
		)
		(fp_line
			(start -0.12065 0.2794)
			(end -0.12065 0.3048)
			(stroke
				(width 0.1)
				(type default)
			)
			(layer "F.Fab")
		)
		(fp_line
			(start -0.12065 0.3048)
			(end -0.67945 0.3048)
			(stroke
				(width 0.1)
				(type default)
			)
			(layer "F.Fab")
		)
		(fp_line
			(start 0.120396 0.2794)
			(end -0.12065 0.2794)
			(stroke
				(width 0.1)
				(type default)
			)
			(layer "F.Fab")
		)
		(fp_line
			(start 0.120396 0.3048)
			(end 0.120396 0.2794)
			(stroke
				(width 0.1)
				(type default)
			)
			(layer "F.Fab")
		)
		(fp_line
			(start 0.12065 -0.3048)
			(end 0.67945 -0.3048)
			(stroke
				(width 0.1)
				(type default)
			)
			(layer "F.Fab")
		)
		(fp_line
			(start 0.12065 -0.2794)
			(end 0.12065 -0.3048)
			(stroke
				(width 0.1)
				(type default)
			)
			(layer "F.Fab")
		)
		(fp_line
			(start 0.67945 -0.3048)
			(end 0.67945 0.3048)
			(stroke
				(width 0.1)
				(type default)
			)
			(layer "F.Fab")
		)
		(fp_line
			(start 0.67945 0.3048)
			(end 0.120396 0.3048)
			(stroke
				(width 0.1)
				(type default)
			)
			(layer "F.Fab")
		)
		(pad "1" smd circle
			(at -0.40005 0)
			(size 0 0)
			(layers "F.Cu" "F.Mask" "F.Paste")
			(net "HP_LVC3_OCP_V3_1_R_EN")
		)
		(pad "2" smd circle
			(at 0.40005 0)
			(size 0 0)
			(layers "F.Cu" "F.Mask" "F.Paste")
			(net "P3V3_OCP_SFF_EN_R")
		)
	)
)
